#ISCELL
  mstr_misc dns *
  *
#ISCELL
  pure_quanta quanta_title_block_c *
  *
#CELL
  pure_quanta mosfet_n *
  page185_i1
#ISCELL
  pure_quanta_power universal_gnd *
  page185_i10
#CELL
  pure_quanta q_cap *
  page185_i100
#CELL
  pure_quanta q_res *
  page185_i101
#ISCELL
  pure_quanta_power universal_gnd *
  page185_i102
#ISCELL
  pure_quanta_power vcc_core *
  page185_i103
#CELL
  pure_quanta q_res *
  page185_i104
#CELL
  pure_quanta q_res *
  page185_i105
#ISCELL
  pure_quanta_power universal_gnd *
  page185_i107
#ISCELL
  pure_quanta_power universal_gnd *
  page185_i108
#ISCELL
  pure_quanta_power vcc_core *
  page185_i109
#ISCELL
  standard offpage *
  page185_i110
#ISCELL
  pure_quanta_power vcc_core *
  page185_i111
#CELL
  pure_quanta q_res *
  page185_i112
#CELL
  pure_quanta q_res *
  page185_i113
#CELL
  pure_quanta q_cap *
  page185_i114
#ISCELL
  pure_quanta_power universal_gnd *
  page185_i116
#CELL
  pure_quanta q_cap *
  page185_i118
#ISCELL
  standard offpage *
  page185_i119
#ISCELL
  pure_quanta_power universal_gnd *
  page185_i12
#CELL
  pure_quanta q_cap *
  page185_i13
#CELL
  pure_quanta q_res *
  page185_i139
#ISCELL
  pure_quanta_power vcc_core *
  page185_i14
#CELL
  pure_quanta q_cap *
  page185_i140
#ISCELL
  pure_quanta_power universal_gnd *
  page185_i141
#ISCELL
  pure_quanta_power universal_gnd *
  page185_i144
#ISCELL
  pure_quanta_power universal_gnd *
  page185_i145
#CELL
  pure_quanta q_res *
  page185_i148
#CELL
  pure_quanta q_res *
  page185_i149
#ISCELL
  standard offpage *
  page185_i15
#ISCELL
  standard offpage *
  page185_i150
#CELL
  pure_quanta q_res *
  page185_i151
#ISCELL
  standard offpage *
  page185_i152
#ISCELL
  standard offpage *
  page185_i153
#CELL
  pure_quanta mosfet_pch_gds_esd_protected *
  page185_i154
#ISCELL
  pure_quanta_power universal_gnd *
  page185_i155
#CELL
  pure_quanta q_cap *
  page185_i156
#ISCELL
  pure_quanta_power universal_gnd *
  page185_i157
#CELL
  pure_quanta q_cap *
  page185_i158
#ISCELL
  standard offpage *
  page185_i173
#ISCELL
  pure_quanta_power vcc_core *
  page185_i174
#CELL
  pure_quanta q_cap *
  page185_i175
#ISCELL
  standard offpage *
  page185_i176
#ISCELL
  pure_quanta_power vcc_core *
  page185_i177
#CELL
  pure_quanta q_res *
  page185_i178
#CELL
  pure_quanta q_res *
  page185_i179
#CELL
  pure_quanta q_res *
  page185_i180
#CELL
  pure_quanta q_res *
  page185_i181
#ISCELL
  pure_quanta_power universal_gnd *
  page185_i182
#ISCELL
  standard offpage *
  page185_i183
#ISCELL
  standard offpage *
  page185_i184
#CELL
  pure_quanta q_res *
  page185_i185
#CELL
  pure_quanta q_res *
  page185_i186
#CELL
  pure_quanta q_res *
  page185_i187
#CELL
  pure_quanta q_cap *
  page185_i214
#CELL
  pure_quanta q_cap *
  page185_i215
#ISCELL
  pure_quanta_power universal_gnd *
  page185_i216
#CELL
  pure_quanta q_cap *
  page185_i217
#ISCELL
  standard offpage *
  page185_i218
#ISCELL
  standard offpage *
  page185_i219
#ISCELL
  standard offpage *
  page185_i220
#ISCELL
  standard offpage *
  page185_i221
#ISCELL
  standard offpage *
  page185_i222
#ISCELL
  standard offpage *
  page185_i223
#ISCELL
  standard offpage *
  page185_i224
#ISCELL
  standard offpage *
  page185_i225
#ISCELL
  standard offpage *
  page185_i226
#ISCELL
  standard offpage *
  page185_i227
#ISCELL
  standard offpage *
  page185_i228
#ISCELL
  standard offpage *
  page185_i229
#CELL
  pure_quanta q_res *
  page185_i230
#ISCELL
  pure_quanta_power universal_gnd *
  page185_i231
#ISCELL
  pure_quanta_power universal_gnd *
  page185_i232
#CELL
  pure_quanta q_res *
  page185_i233
#ISCELL
  standard offpage *
  page185_i234
#ISCELL
  standard offpage *
  page185_i235
#ISCELL
  standard offpage *
  page185_i236
#ISCELL
  standard offpage *
  page185_i237
#ISCELL
  standard offpage *
  page185_i238
#ISCELL
  standard offpage *
  page185_i239
#ISCELL
  pure_quanta_power universal_gnd *
  page185_i240
#CELL
  pure_quanta q_res *
  page185_i241
#ISCELL
  pure_quanta_power universal_gnd *
  page185_i242
#CELL
  pure_quanta q_res *
  page185_i243
#CELL
  pure_quanta q_res *
  page185_i3
#CELL
  pure_quanta q_cap *
  page185_i35
#CELL
  pure_quanta q_cap *
  page185_i36
#ISCELL
  pure_quanta_power universal_gnd *
  page185_i37
#ISCELL
  pure_quanta_power universal_gnd *
  page185_i38
#CELL
  pure_quanta q_res *
  page185_i4
#CELL
  pure_quanta q_cap *
  page185_i42
#CELL
  pure_quanta q_res *
  page185_i43
#ISCELL
  pure_quanta_power universal_gnd *
  page185_i44
#ISCELL
  standard offpage *
  page185_i45
#ISCELL
  pure_quanta_power vcc_core *
  page185_i46
#CELL
  pure_quanta q_res *
  page185_i47
#CELL
  pure_quanta q_cap *
  page185_i49
#ISCELL
  pure_quanta_power universal_gnd *
  page185_i5
#ISCELL
  pure_quanta_power universal_gnd *
  page185_i50
#ISCELL
  standard offpage *
  page185_i53
#CELL
  pure_quanta q_res *
  page185_i55
#CELL
  pure_quanta q_res *
  page185_i56
#CELL
  pure_quanta q_res *
  page185_i57
#CELL
  pure_quanta q_res *
  page185_i58
#ISCELL
  pure_quanta_power vcc_core *
  page185_i59
#ISCELL
  pure_quanta_power vcc_core *
  page185_i6
#CELL
  pure_quanta q_res *
  page185_i62
#ISCELL
  pure_quanta_power universal_gnd *
  page185_i64
#ISCELL
  pure_quanta_power universal_gnd *
  page185_i65
#CELL
  pure_quanta q_res *
  page185_i67
#CELL
  pure_quanta q_res *
  page185_i68
#CELL
  pure_quanta raa229620gnpha0 *
  page185_i7
#ISCELL
  standard offpage *
  page185_i73
#ISCELL
  standard offpage *
  page185_i74
#ISCELL
  standard offpage *
  page185_i75
#CELL
  pure_quanta q_cap *
  page185_i76
#CELL
  pure_quanta q_res *
  page185_i77
#ISCELL
  standard offpage *
  page185_i79
#CELL
  pure_quanta q_cap *
  page185_i8
#ISCELL
  standard offpage *
  page185_i80
#CELL
  pure_quanta q_res *
  page185_i81
#CELL
  pure_quanta q_res *
  page185_i82
#ISCELL
  pure_quanta_power universal_gnd *
  page185_i83
#ISCELL
  pure_quanta_power vcc_core *
  page185_i84
#ISCELL
  pure_quanta_power vcc_core *
  page185_i85
#CELL
  pure_quanta q_res *
  page185_i86
#CELL
  pure_quanta q_cap *
  page185_i87
#CELL
  pure_quanta q_res *
  page185_i88
#CELL
  pure_quanta q_res *
  page185_i90
#ISCELL
  pure_quanta_power universal_gnd *
  page185_i91
#ISCELL
  standard offpage *
  page185_i92
#ISCELL
  standard offpage *
  page185_i93
#ISCELL
  pure_quanta_power universal_gnd *
  page185_i99
